# T6G (Grand Teton) — schematic netlist excerpt (pin names and nets, part order shuffled) for the footprints in the layout excerpt that follows; sources: Cadence DE-HDL packaged netlist, KiCad conversion of 04192023_DAF0TMB3IC0_F0TG_MB_C_brd_V02_OCP.brd

C1504  Q_CAP  0.1UF 16V 10% X7R  pkg C0402  page 172 : A = PVDD18_S5_P0 ; B = GND
C2012  Q_CAP  0.1UF 25V 10% X7R  pkg 0402  page 237 : A = P3V3_AUX ; B = GND

(kicad_pcb
	(version 20260206)
	(generator "pcbnew")
	(generator_version "10.0")
	(general
		(thickness 1.6)
		(legacy_teardrops no)
	)
	(paper "A4")
	(title_block
		(title "04192023_DAF0TMB3IC0_F0TG_MB_C_brd_V02_OCP.brd")
		(comment 1 "Grand Teton / footprints 1246-1247 of 8354")
	)
	(layers
		(0 "F.Cu" signal "TOP")
		(4 "In1.Cu" signal "GND")
		(6 "In2.Cu" signal "IN1")
		(8 "In3.Cu" signal "GND1")
		(10 "In4.Cu" signal "IN2")
		(12 "In5.Cu" signal "GND2")
		(14 "In6.Cu" signal "IN3")
		(16 "In7.Cu" signal "GND3")
		(18 "In8.Cu" signal "VCC")
		(20 "In9.Cu" signal "VCC1")
		(22 "In10.Cu" signal "GND4")
		(24 "In11.Cu" signal "IN4")
		(26 "In12.Cu" signal "GND5")
		(28 "In13.Cu" signal "IN5")
		(30 "In14.Cu" signal "GND6")
		(32 "In15.Cu" signal "IN6")
		(34 "In16.Cu" signal "GND7")
		(2 "B.Cu" signal "BOTTOM")
		(9 "F.Adhes" user "F.Adhesive")
		(11 "B.Adhes" user "B.Adhesive")
		(13 "F.Paste" user "Package Geometry/Pastemask Top")
		(15 "B.Paste" user "Package Geometry/Pastemask Bottom")
		(5 "F.SilkS" user "Ref Des/Silkscreen Top")
		(7 "B.SilkS" user "Ref Des/Silkscreen Bottom")
		(1 "F.Mask" user "Board Geometry/Soldermask Top")
		(3 "B.Mask" user "Board Geometry/Soldermask Bottom")
		(17 "Dwgs.User" user "User.Drawings")
		(19 "Cmts.User" user "User.Comments")
		(21 "Eco1.User" user "User.Eco1")
		(23 "Eco2.User" user "User.Eco2")
		(25 "Edge.Cuts" user "Board Geometry/Outline")
		(27 "Margin" user)
		(31 "F.CrtYd" user "Package Geometry/Place Bound Top")
		(29 "B.CrtYd" user "Package Geometry/Place Bound Bottom")
		(35 "F.Fab" user "Ref Des/Assembly Top")
		(33 "B.Fab" user "Ref Des/Assembly Bottom")
	)
	(footprint ""
		(layer "F.Cu")
		(at 123.127516 -57.137808 90)
		(property "Reference" "C1504"
			(at 0 0 90)
			(layer "F.SilkS")
			(hide yes)
			(effects
				(font
					(size 1.27 1.27)
				)
			)
		)
		(property "Value" ""
			(at 0 0 90)
			(layer "F.Fab")
			(effects
				(font
					(size 1.27 1.27)
				)
			)
		)
		(duplicate_pad_numbers_are_jumpers no)
		(fp_line
			(start 0.7874 -0.4064)
			(end 0.7874 0.4064)
			(stroke
				(width 0.1524)
				(type default)
			)
			(layer "F.SilkS")
		)
		(fp_line
			(start -0.7874 -0.4064)
			(end 0.7874 -0.4064)
			(stroke
				(width 0.1524)
				(type default)
			)
			(layer "F.SilkS")
		)
		(fp_line
			(start 0.7874 0.4064)
			(end -0.7874 0.4064)
			(stroke
				(width 0.1524)
				(type default)
			)
			(layer "F.SilkS")
		)
		(fp_line
			(start -0.7874 0.4064)
			(end -0.7874 -0.4064)
			(stroke
				(width 0.1524)
				(type default)
			)
			(layer "F.SilkS")
		)
		(fp_line
			(start -0.12065 -0.305054)
			(end -0.12065 -0.2794)
			(stroke
				(width 0.1)
				(type default)
			)
			(layer "F.Fab")
		)
		(fp_line
			(start -0.67945 -0.305054)
			(end -0.12065 -0.305054)
			(stroke
				(width 0.1)
				(type default)
			)
			(layer "F.Fab")
		)
		(fp_line
			(start 0.67945 -0.3048)
			(end 0.67945 0.3048)
			(stroke
				(width 0.1)
				(type default)
			)
			(layer "F.Fab")
		)
		(fp_line
			(start 0.12065 -0.3048)
			(end 0.67945 -0.3048)
			(stroke
				(width 0.1)
				(type default)
			)
			(layer "F.Fab")
		)
		(fp_line
			(start 0.12065 -0.2794)
			(end 0.12065 -0.3048)
			(stroke
				(width 0.1)
				(type default)
			)
			(layer "F.Fab")
		)
		(fp_line
			(start -0.12065 -0.2794)
			(end 0.12065 -0.2794)
			(stroke
				(width 0.1)
				(type default)
			)
			(layer "F.Fab")
		)
		(fp_line
			(start 0.120396 0.2794)
			(end -0.12065 0.2794)
			(stroke
				(width 0.1)
				(type default)
			)
			(layer "F.Fab")
		)
		(fp_line
			(start -0.12065 0.2794)
			(end -0.12065 0.3048)
			(stroke
				(width 0.1)
				(type default)
			)
			(layer "F.Fab")
		)
		(fp_line
			(start 0.67945 0.3048)
			(end 0.120396 0.3048)
			(stroke
				(width 0.1)
				(type default)
			)
			(layer "F.Fab")
		)
		(fp_line
			(start 0.120396 0.3048)
			(end 0.120396 0.2794)
			(stroke
				(width 0.1)
				(type default)
			)
			(layer "F.Fab")
		)
		(fp_line
			(start -0.12065 0.3048)
			(end -0.67945 0.3048)
			(stroke
				(width 0.1)
				(type default)
			)
			(layer "F.Fab")
		)
		(fp_line
			(start -0.67945 0.3048)
			(end -0.67945 -0.305054)
			(stroke
				(width 0.1)
				(type default)
			)
			(layer "F.Fab")
		)
		(pad "1" smd circle
			(at -0.40005 0 90)
			(size 0 0)
			(layers "F.Cu" "F.Mask" "F.Paste")
			(net "PVDD18_S5_P0")
		)
		(pad "2" smd circle
			(at 0.40005 0 90)
			(size 0 0)
			(layers "F.Cu" "F.Mask" "F.Paste")
			(net "GND")
		)
	)
	(footprint ""
		(layer "F.Cu")
		(at 75.705462 -38.532562)
		(property "Reference" "C2012"
			(at 0 0 0)
			(layer "F.SilkS")
			(hide yes)
			(effects
				(font
					(size 1.27 1.27)
				)
			)
		)
		(property "Value" ""
			(at 0 0 0)
			(layer "F.Fab")
			(effects
				(font
					(size 1.27 1.27)
				)
			)
		)
		(duplicate_pad_numbers_are_jumpers no)
		(fp_line
			(start -0.7874 -0.4064)
			(end 0.7874 -0.4064)
			(stroke
				(width 0.1524)
				(type default)
			)
			(layer "F.SilkS")
		)
		(fp_line
			(start -0.7874 0.4064)
			(end -0.7874 -0.4064)
			(stroke
				(width 0.1524)
				(type default)
			)
			(layer "F.SilkS")
		)
		(fp_line
			(start 0.7874 -0.4064)
			(end 0.7874 0.4064)
			(stroke
				(width 0.1524)
				(type default)
			)
			(layer "F.SilkS")
		)
		(fp_line
			(start 0.7874 0.4064)
			(end -0.7874 0.4064)
			(stroke
				(width 0.1524)
				(type default)
			)
			(layer "F.SilkS")
		)
		(fp_line
			(start -0.67945 -0.305054)
			(end -0.12065 -0.305054)
			(stroke
				(width 0.1)
				(type default)
			)
			(layer "F.Fab")
		)
		(fp_line
			(start -0.67945 0.3048)
			(end -0.67945 -0.305054)
			(stroke
				(width 0.1)
				(type default)
			)
			(layer "F.Fab")
		)
		(fp_line
			(start -0.12065 -0.305054)
			(end -0.12065 -0.2794)
			(stroke
				(width 0.1)
				(type default)
			)
			(layer "F.Fab")
		)
		(fp_line
			(start -0.12065 -0.2794)
			(end 0.12065 -0.2794)
			(stroke
				(width 0.1)
				(type default)
			)
			(layer "F.Fab")
		)
		(fp_line
			(start -0.12065 0.2794)
			(end -0.12065 0.3048)
			(stroke
				(width 0.1)
				(type default)
			)
			(layer "F.Fab")
		)
		(fp_line
			(start -0.12065 0.3048)
			(end -0.67945 0.3048)
			(stroke
				(width 0.1)
				(type default)
			)
			(layer "F.Fab")
		)
		(fp_line
			(start 0.120396 0.2794)
			(end -0.12065 0.2794)
			(stroke
				(width 0.1)
				(type default)
			)
			(layer "F.Fab")
		)
		(fp_line
			(start 0.120396 0.3048)
			(end 0.120396 0.2794)
			(stroke
				(width 0.1)
				(type default)
			)
			(layer "F.Fab")
		)
		(fp_line
			(start 0.12065 -0.3048)
			(end 0.67945 -0.3048)
			(stroke
				(width 0.1)
				(type default)
			)
			(layer "F.Fab")
		)
		(fp_line
			(start 0.12065 -0.2794)
			(end 0.12065 -0.3048)
			(stroke
				(width 0.1)
				(type default)
			)
			(layer "F.Fab")
		)
		(fp_line
			(start 0.67945 -0.3048)
			(end 0.67945 0.3048)
			(stroke
				(width 0.1)
				(type default)
			)
			(layer "F.Fab")
		)
		(fp_line
			(start 0.67945 0.3048)
			(end 0.120396 0.3048)
			(stroke
				(width 0.1)
				(type default)
			)
			(layer "F.Fab")
		)
		(pad "1" smd circle
			(at -0.40005 0)
			(size 0 0)
			(layers "F.Cu" "F.Mask" "F.Paste")
			(net "P3V3_AUX")
		)
		(pad "2" smd circle
			(at 0.40005 0)
			(size 0 0)
			(layers "F.Cu" "F.Mask" "F.Paste")
			(net "GND")
		)
	)
)
